(kicad_pcb
	(version 20260206)
	(generator "pcbnew")
	(generator_version "10.0")
	(general
		(thickness 1.6)
		(legacy_teardrops no)
	)
	(paper "A4")
	(title_block
		(title "Bryce Canyon_F.DPB_16315-1-OCP.brd")
		(comment 1 "Bryce Canyon / footprints 1903-1909 of 2223")
	)
	(layers
		(0 "F.Cu" signal "TOP")
		(4 "In1.Cu" signal "L2GND")
		(6 "In2.Cu" signal "L3")
		(8 "In3.Cu" signal "L4GND")
		(10 "In4.Cu" signal "L5")
		(12 "In5.Cu" signal "L6VCC")
		(14 "In6.Cu" signal "L7VCC")
		(16 "In7.Cu" signal "L8")
		(18 "In8.Cu" signal "L9GND")
		(20 "In9.Cu" signal "L10")
		(22 "In10.Cu" signal "L11GND")
		(2 "B.Cu" signal "BOTTOM")
		(9 "F.Adhes" user "F.Adhesive")
		(11 "B.Adhes" user "B.Adhesive")
		(13 "F.Paste" user "Package Geometry/Pastemask Top")
		(15 "B.Paste" user "Package Geometry/Pastemask Bottom")
		(5 "F.SilkS" user "Ref Des/Silkscreen Top")
		(7 "B.SilkS" user "Ref Des/Silkscreen Bottom")
		(1 "F.Mask" user "Board Geometry/Soldermask Top")
		(3 "B.Mask" user "Board Geometry/Soldermask Bottom")
		(17 "Dwgs.User" user "User.Drawings")
		(19 "Cmts.User" user "User.Comments")
		(21 "Eco1.User" user "User.Eco1")
		(23 "Eco2.User" user "User.Eco2")
		(25 "Edge.Cuts" user "Board Geometry/Outline")
		(27 "Margin" user)
		(31 "F.CrtYd" user "Package Geometry/Place Bound Top")
		(29 "B.CrtYd" user "Package Geometry/Place Bound Bottom")
		(35 "F.Fab" user "Ref Des/Assembly Top")
		(33 "B.Fab" user "Ref Des/Assembly Bottom")
	)
	(footprint ""
		(layer "F.Cu")
		(at 377.846082 -290.591748 90)
		(property "Reference" "R592"
			(at 0 0 90)
			(layer "F.SilkS")
			(hide yes)
			(effects
				(font
					(size 1.27 1.27)
				)
			)
		)
		(property "Value" "4K7R2J-2-GP"
			(at 0.064008 -3.993896 90)
			(unlocked yes)
			(layer "F.Fab")
			(hide yes)
			(effects
				(font
					(size 1.016 1.016)
					(thickness 0.1524)
				)
			)
		)
		(property "Device Type" "R402H16"
			(at 0.064008 -5.517896 90)
			(unlocked yes)
			(layer "F.Fab")
			(hide yes)
			(effects
				(font
					(size 1.016 1.016)
					(thickness 0.1524)
				)
			)
		)
		(duplicate_pad_numbers_are_jumpers no)
		(fp_line
			(start 0.508 -0.9398)
			(end -0.508 -0.9398)
			(stroke
				(width 0.1524)
				(type default)
			)
			(layer "F.SilkS")
		)
		(fp_line
			(start -0.508 -0.9398)
			(end -0.508 0.9398)
			(stroke
				(width 0.1524)
				(type default)
			)
			(layer "F.SilkS")
		)
		(fp_rect
			(start -0.508 0.9398)
			(end 0.508 -0.9398)
			(stroke
				(width 0)
				(type default)
			)
			(fill no)
			(layer "F.CrtYd")
		)
		(fp_rect
			(start -0.508 0.9398)
			(end 0.508 -0.9398)
			(stroke
				(width 0)
				(type default)
			)
			(fill no)
			(layer "F.Fab")
		)
		(pad "1" smd custom
			(at 0 -0.4445 90)
			(size 0.1397 0.1397)
			(layers "F.Cu" "F.Mask" "F.Paste")
			(net "DRIVE_B_32_FLT_LED")
			(options
				(clearance outline)
				(anchor circle)
			)
			(primitives
				(gr_poly
					(pts
						(arc
							(start -0.1778 -0.2794)
							(mid -0.249642 -0.249642)
							(end -0.2794 -0.1778)
						)
						(arc
							(start -0.2794 0.1778)
							(mid -0.249642 0.249642)
							(end -0.1778 0.2794)
						)
						(arc
							(start 0.1778 0.2794)
							(mid 0.249642 0.249642)
							(end 0.2794 0.1778)
						)
						(arc
							(start 0.2794 -0.1778)
							(mid 0.249642 -0.249642)
							(end 0.1778 -0.2794)
						)
					)
					(width 0)
					(fill yes)
				)
			)
		)
		(pad "2" smd custom
			(at 0 0.4445 90)
			(size 0.1397 0.1397)
			(layers "F.Cu" "F.Mask" "F.Paste")
			(net "GND")
			(options
				(clearance outline)
				(anchor circle)
			)
			(primitives
				(gr_poly
					(pts
						(arc
							(start -0.1778 -0.2794)
							(mid -0.249642 -0.249642)
							(end -0.2794 -0.1778)
						)
						(arc
							(start -0.2794 0.1778)
							(mid -0.249642 0.249642)
							(end -0.1778 0.2794)
						)
						(arc
							(start 0.1778 0.2794)
							(mid 0.249642 0.249642)
							(end 0.2794 0.1778)
						)
						(arc
							(start 0.2794 -0.1778)
							(mid 0.249642 -0.249642)
							(end 0.1778 -0.2794)
						)
					)
					(width 0)
					(fill yes)
				)
			)
		)
	)
	(footprint ""
		(layer "F.Cu")
		(at 51.511708 -157.605984 90)
		(property "Reference" "R446"
			(at 0 0 90)
			(layer "F.SilkS")
			(hide yes)
			(effects
				(font
					(size 1.27 1.27)
				)
			)
		)
		(property "Value" "0R2J-2-GP"
			(at 0.064008 -3.993896 90)
			(unlocked yes)
			(layer "F.Fab")
			(hide yes)
			(effects
				(font
					(size 1.016 1.016)
					(thickness 0.1524)
				)
			)
		)
		(property "Device Type" "R402H16"
			(at 0.064008 -5.517896 90)
			(unlocked yes)
			(layer "F.Fab")
			(hide yes)
			(effects
				(font
					(size 1.016 1.016)
					(thickness 0.1524)
				)
			)
		)
		(duplicate_pad_numbers_are_jumpers no)
		(fp_line
			(start 0.508 -0.9398)
			(end -0.508 -0.9398)
			(stroke
				(width 0.1524)
				(type default)
			)
			(layer "F.SilkS")
		)
		(fp_line
			(start -0.508 -0.9398)
			(end -0.508 0.9398)
			(stroke
				(width 0.1524)
				(type default)
			)
			(layer "F.SilkS")
		)
		(fp_rect
			(start -0.508 0.9398)
			(end 0.508 -0.9398)
			(stroke
				(width 0)
				(type default)
			)
			(fill no)
			(layer "F.CrtYd")
		)
		(fp_rect
			(start -0.508 0.9398)
			(end 0.508 -0.9398)
			(stroke
				(width 0)
				(type default)
			)
			(fill no)
			(layer "F.Fab")
		)
		(pad "1" smd custom
			(at 0 -0.4445 90)
			(size 0.1397 0.1397)
			(layers "F.Cu" "F.Mask" "F.Paste")
			(net "SW_HDD_G13")
			(options
				(clearance outline)
				(anchor circle)
			)
			(primitives
				(gr_poly
					(pts
						(arc
							(start -0.1778 -0.2794)
							(mid -0.249642 -0.249642)
							(end -0.2794 -0.1778)
						)
						(arc
							(start -0.2794 0.1778)
							(mid -0.249642 0.249642)
							(end -0.1778 0.2794)
						)
						(arc
							(start 0.1778 0.2794)
							(mid 0.249642 0.249642)
							(end 0.2794 0.1778)
						)
						(arc
							(start 0.2794 -0.1778)
							(mid 0.249642 -0.249642)
							(end 0.1778 -0.2794)
						)
					)
					(width 0)
					(fill yes)
				)
			)
		)
		(pad "2" smd custom
			(at 0 0.4445 90)
			(size 0.1397 0.1397)
			(layers "F.Cu" "F.Mask" "F.Paste")
			(net "SW_HDD_R13")
			(options
				(clearance outline)
				(anchor circle)
			)
			(primitives
				(gr_poly
					(pts
						(arc
							(start -0.1778 -0.2794)
							(mid -0.249642 -0.249642)
							(end -0.2794 -0.1778)
						)
						(arc
							(start -0.2794 0.1778)
							(mid -0.249642 0.249642)
							(end -0.1778 0.2794)
						)
						(arc
							(start 0.1778 0.2794)
							(mid 0.249642 0.249642)
							(end 0.2794 0.1778)
						)
						(arc
							(start 0.2794 -0.1778)
							(mid 0.249642 -0.249642)
							(end 0.1778 -0.2794)
						)
					)
					(width 0)
					(fill yes)
				)
			)
		)
	)
	(footprint ""
		(layer "F.Cu")
		(at 78.298548 -277.183342 180)
		(property "Reference" "R192"
			(at 0 0 180)
			(layer "F.SilkS")
			(hide yes)
			(effects
				(font
					(size 1.27 1.27)
				)
			)
		)
		(property "Value" "200KR2F-L-GP"
			(at 0.064008 -3.993896 180)
			(unlocked yes)
			(layer "F.Fab")
			(hide yes)
			(effects
				(font
					(size 1.016 1.016)
					(thickness 0.1524)
				)
			)
		)
		(property "Device Type" "R402H16"
			(at 0.064008 -5.517896 180)
			(unlocked yes)
			(layer "F.Fab")
			(hide yes)
			(effects
				(font
					(size 1.016 1.016)
					(thickness 0.1524)
				)
			)
		)
		(duplicate_pad_numbers_are_jumpers no)
		(fp_line
			(start 0.508 -0.9398)
			(end -0.508 -0.9398)
			(stroke
				(width 0.1524)
				(type default)
			)
			(layer "F.SilkS")
		)
		(fp_line
			(start -0.508 -0.9398)
			(end -0.508 0.9398)
			(stroke
				(width 0.1524)
				(type default)
			)
			(layer "F.SilkS")
		)
		(fp_rect
			(start -0.508 0.9398)
			(end 0.508 -0.9398)
			(stroke
				(width 0)
				(type default)
			)
			(fill no)
			(layer "F.CrtYd")
		)
		(fp_rect
			(start -0.508 0.9398)
			(end 0.508 -0.9398)
			(stroke
				(width 0)
				(type default)
			)
			(fill no)
			(layer "F.Fab")
		)
		(pad "1" smd custom
			(at 0 -0.4445 180)
			(size 0.1397 0.1397)
			(layers "F.Cu" "F.Mask" "F.Paste")
			(net "SW_HDD_R2")
			(options
				(clearance outline)
				(anchor circle)
			)
			(primitives
				(gr_poly
					(pts
						(arc
							(start -0.1778 -0.2794)
							(mid -0.249642 -0.249642)
							(end -0.2794 -0.1778)
						)
						(arc
							(start -0.2794 0.1778)
							(mid -0.249642 0.249642)
							(end -0.1778 0.2794)
						)
						(arc
							(start 0.1778 0.2794)
							(mid 0.249642 0.249642)
							(end 0.2794 0.1778)
						)
						(arc
							(start 0.2794 -0.1778)
							(mid 0.249642 -0.249642)
							(end 0.1778 -0.2794)
						)
					)
					(width 0)
					(fill yes)
				)
			)
		)
		(pad "2" smd custom
			(at 0 0.4445 180)
			(size 0.1397 0.1397)
			(layers "F.Cu" "F.Mask" "F.Paste")
			(net "SW_HDD_N2")
			(options
				(clearance outline)
				(anchor circle)
			)
			(primitives
				(gr_poly
					(pts
						(arc
							(start -0.1778 -0.2794)
							(mid -0.249642 -0.249642)
							(end -0.2794 -0.1778)
						)
						(arc
							(start -0.2794 0.1778)
							(mid -0.249642 0.249642)
							(end -0.1778 0.2794)
						)
						(arc
							(start 0.1778 0.2794)
							(mid 0.249642 0.249642)
							(end 0.2794 0.1778)
						)
						(arc
							(start 0.2794 -0.1778)
							(mid 0.249642 -0.249642)
							(end 0.1778 -0.2794)
						)
					)
					(width 0)
					(fill yes)
				)
			)
		)
	)
	(footprint ""
		(layer "F.Cu")
		(at 363.655102 -272.585942)
		(property "Reference" "R304"
			(at 0 0 0)
			(layer "F.SilkS")
			(hide yes)
			(effects
				(font
					(size 1.27 1.27)
				)
			)
		)
		(property "Value" "4K7R2J-2-GP"
			(at 0.064008 -3.993896 0)
			(unlocked yes)
			(layer "F.Fab")
			(hide yes)
			(effects
				(font
					(size 1.016 1.016)
					(thickness 0.1524)
				)
			)
		)
		(property "Device Type" "R402H16"
			(at 0.064008 -5.517896 0)
			(unlocked yes)
			(layer "F.Fab")
			(hide yes)
			(effects
				(font
					(size 1.016 1.016)
					(thickness 0.1524)
				)
			)
		)
		(duplicate_pad_numbers_are_jumpers no)
		(fp_line
			(start -0.508 -0.9398)
			(end -0.508 0.9398)
			(stroke
				(width 0.1524)
				(type default)
			)
			(layer "F.SilkS")
		)
		(fp_line
			(start 0.508 -0.9398)
			(end -0.508 -0.9398)
			(stroke
				(width 0.1524)
				(type default)
			)
			(layer "F.SilkS")
		)
		(fp_rect
			(start -0.508 0.9398)
			(end 0.508 -0.9398)
			(stroke
				(width 0)
				(type default)
			)
			(fill no)
			(layer "F.CrtYd")
		)
		(fp_rect
			(start -0.508 0.9398)
			(end 0.508 -0.9398)
			(stroke
				(width 0)
				(type default)
			)
			(fill no)
			(layer "F.Fab")
		)
		(pad "1" smd custom
			(at 0 -0.4445)
			(size 0.1397 0.1397)
			(layers "F.Cu" "F.Mask" "F.Paste")
			(net "SW_PWR_R_HDD7")
			(options
				(clearance outline)
				(anchor circle)
			)
			(primitives
				(gr_poly
					(pts
						(arc
							(start -0.1778 -0.2794)
							(mid -0.249642 -0.249642)
							(end -0.2794 -0.1778)
						)
						(arc
							(start -0.2794 0.1778)
							(mid -0.249642 0.249642)
							(end -0.1778 0.2794)
						)
						(arc
							(start 0.1778 0.2794)
							(mid 0.249642 0.249642)
							(end 0.2794 0.1778)
						)
						(arc
							(start 0.2794 -0.1778)
							(mid 0.249642 -0.249642)
							(end 0.1778 -0.2794)
						)
					)
					(width 0)
					(fill yes)
				)
			)
		)
		(pad "2" smd custom
			(at 0 0.4445)
			(size 0.1397 0.1397)
			(layers "F.Cu" "F.Mask" "F.Paste")
			(net "GND")
			(options
				(clearance outline)
				(anchor circle)
			)
			(primitives
				(gr_poly
					(pts
						(arc
							(start -0.1778 -0.2794)
							(mid -0.249642 -0.249642)
							(end -0.2794 -0.1778)
						)
						(arc
							(start -0.2794 0.1778)
							(mid -0.249642 0.249642)
							(end -0.1778 0.2794)
						)
						(arc
							(start 0.1778 0.2794)
							(mid 0.249642 0.249642)
							(end 0.2794 0.1778)
						)
						(arc
							(start 0.2794 -0.1778)
							(mid 0.249642 -0.249642)
							(end 0.1778 -0.2794)
						)
					)
					(width 0)
					(fill yes)
				)
			)
		)
	)
	(footprint ""
		(layer "F.Cu")
		(at 398.83715 -160.735518 180)
		(property "Reference" "R607"
			(at 0 0 180)
			(layer "F.SilkS")
			(hide yes)
			(effects
				(font
					(size 1.27 1.27)
				)
			)
		)
		(property "Value" "0R2J-2-GP"
			(at 0.064008 -3.993896 180)
			(unlocked yes)
			(layer "F.Fab")
			(hide yes)
			(effects
				(font
					(size 1.016 1.016)
					(thickness 0.1524)
				)
			)
		)
		(property "Device Type" "R402H16"
			(at 0.064008 -5.517896 180)
			(unlocked yes)
			(layer "F.Fab")
			(hide yes)
			(effects
				(font
					(size 1.016 1.016)
					(thickness 0.1524)
				)
			)
		)
		(duplicate_pad_numbers_are_jumpers no)
		(fp_line
			(start 0.508 -0.9398)
			(end -0.508 -0.9398)
			(stroke
				(width 0.1524)
				(type default)
			)
			(layer "F.SilkS")
		)
		(fp_line
			(start -0.508 -0.9398)
			(end -0.508 0.9398)
			(stroke
				(width 0.1524)
				(type default)
			)
			(layer "F.SilkS")
		)
		(fp_rect
			(start -0.508 0.9398)
			(end 0.508 -0.9398)
			(stroke
				(width 0)
				(type default)
			)
			(fill no)
			(layer "F.CrtYd")
		)
		(fp_rect
			(start -0.508 0.9398)
			(end 0.508 -0.9398)
			(stroke
				(width 0)
				(type default)
			)
			(fill no)
			(layer "F.Fab")
		)
		(pad "1" smd custom
			(at 0 -0.4445 180)
			(size 0.1397 0.1397)
			(layers "F.Cu" "F.Mask" "F.Paste")
			(net "SW_HDD_G20")
			(options
				(clearance outline)
				(anchor circle)
			)
			(primitives
				(gr_poly
					(pts
						(arc
							(start -0.1778 -0.2794)
							(mid -0.249642 -0.249642)
							(end -0.2794 -0.1778)
						)
						(arc
							(start -0.2794 0.1778)
							(mid -0.249642 0.249642)
							(end -0.1778 0.2794)
						)
						(arc
							(start 0.1778 0.2794)
							(mid 0.249642 0.249642)
							(end 0.2794 0.1778)
						)
						(arc
							(start 0.2794 -0.1778)
							(mid 0.249642 -0.249642)
							(end 0.1778 -0.2794)
						)
					)
					(width 0)
					(fill yes)
				)
			)
		)
		(pad "2" smd custom
			(at 0 0.4445 180)
			(size 0.1397 0.1397)
			(layers "F.Cu" "F.Mask" "F.Paste")
			(net "SW_HDD_R20")
			(options
				(clearance outline)
				(anchor circle)
			)
			(primitives
				(gr_poly
					(pts
						(arc
							(start -0.1778 -0.2794)
							(mid -0.249642 -0.249642)
							(end -0.2794 -0.1778)
						)
						(arc
							(start -0.2794 0.1778)
							(mid -0.249642 0.249642)
							(end -0.1778 0.2794)
						)
						(arc
							(start 0.1778 0.2794)
							(mid 0.249642 0.249642)
							(end 0.2794 0.1778)
						)
						(arc
							(start 0.2794 -0.1778)
							(mid 0.249642 -0.249642)
							(end 0.1778 -0.2794)
						)
					)
					(width 0)
					(fill yes)
				)
			)
		)
	)
	(footprint ""
		(layer "F.Cu")
		(at 331.47 -73.954894 180)
		(property "Reference" "C435"
			(at 0 0 180)
			(layer "F.SilkS")
			(hide yes)
			(effects
				(font
					(size 1.27 1.27)
				)
			)
		)
		(property "Value" "SC4D7U25V5KX-1-GP"
			(at -0.0762 -6.1214 180)
			(unlocked yes)
			(layer "F.Fab")
			(hide yes)
			(effects
				(font
					(size 1.016 1.016)
					(thickness 0.1524)
				)
			)
		)
		(property "Device Type" "C805H58"
			(at -0.0762 -8.1534 180)
			(unlocked yes)
			(layer "F.Fab")
			(hide yes)
			(effects
				(font
					(size 1.016 1.016)
					(thickness 0.1524)
				)
			)
		)
		(duplicate_pad_numbers_are_jumpers no)
		(fp_line
			(start 0.635 0)
			(end -0.635 0)
			(stroke
				(width 0.508)
				(type default)
			)
			(layer "F.SilkS")
		)
		(fp_rect
			(start -0.9652 1.778)
			(end 0.9652 -1.778)
			(stroke
				(width 0)
				(type default)
			)
			(fill no)
			(layer "F.CrtYd")
		)
		(fp_poly
			(pts
				(xy -0.9652 -1.778) (xy 0.9652 -1.778) (xy 0.9652 1.778) (xy -0.9652 1.778)
			)
			(stroke
				(width 0)
				(type default)
			)
			(fill no)
			(layer "F.Fab")
		)
		(pad "1" smd rect
			(at 0 -0.9652 180)
			(size 1.397 1.143)
			(layers "F.Cu" "F.Mask" "F.Paste")
			(net "P12V_HDD30")
		)
		(pad "2" smd rect
			(at 0 0.9652 180)
			(size 1.397 1.143)
			(layers "F.Cu" "F.Mask" "F.Paste")
			(net "GND")
		)
	)
	(footprint ""
		(layer "F.Cu")
		(at 14.722602 -127.799338 180)
		(property "Reference" "Q239"
			(at 0 0 180)
			(layer "F.SilkS")
			(hide yes)
			(effects
				(font
					(size 1.27 1.27)
				)
			)
		)
		(property "Value" "2N7002K-2-GP"
			(at 0.127 -8.9662 180)
			(unlocked yes)
			(layer "F.Fab")
			(hide yes)
			(effects
				(font
					(size 1.016 1.016)
					(thickness 0.1524)
				)
			)
		)
		(property "Device Type" "SOT23DGS2D4H44"
			(at 0.127 -10.4902 180)
			(unlocked yes)
			(layer "F.Fab")
			(hide yes)
			(effects
				(font
					(size 1.016 1.016)
					(thickness 0.1524)
				)
			)
		)
		(duplicate_pad_numbers_are_jumpers no)
		(fp_line
			(start 1.651 1.778)
			(end 1.651 -1.778)
			(stroke
				(width 0.1524)
				(type default)
			)
			(layer "F.SilkS")
		)
		(fp_line
			(start 1.651 -1.778)
			(end -1.651 -1.778)
			(stroke
				(width 0.1524)
				(type default)
			)
			(layer "F.SilkS")
		)
		(fp_line
			(start -1.651 1.778)
			(end 1.651 1.778)
			(stroke
				(width 0.1524)
				(type default)
			)
			(layer "F.SilkS")
		)
		(fp_line
			(start -1.651 -1.778)
			(end -1.651 1.778)
			(stroke
				(width 0.1524)
				(type default)
			)
			(layer "F.SilkS")
		)
		(fp_poly
			(pts
				(xy -1.778 1.8796) (xy -1.778 -1.8796) (xy 1.778 -1.8796) (xy 1.778 1.8796)
			)
			(stroke
				(width 0)
				(type default)
			)
			(fill no)
			(layer "F.CrtYd")
		)
		(fp_poly
			(pts
				(xy -1.778 1.8796) (xy -1.778 -1.8796) (xy 1.778 -1.8796) (xy 1.778 1.8796)
			)
			(stroke
				(width 0)
				(type default)
			)
			(fill no)
			(layer "F.Fab")
		)
		(pad "D" smd custom
			(at 0 -0.9525 180)
			(size 0.1905 0.1905)
			(layers "F.Cu" "F.Mask" "F.Paste")
			(net "FLT_HDD12_N")
			(options
				(clearance outline)
				(anchor circle)
			)
			(primitives
				(gr_poly
					(pts
						(arc
							(start -0.1778 0.5715)
							(mid -0.321484 0.511984)
							(end -0.381 0.3683)
						)
						(arc
							(start -0.381 -0.3683)
							(mid -0.321484 -0.511984)
							(end -0.1778 -0.5715)
						)
						(arc
							(start 0.1778 -0.5715)
							(mid 0.321484 -0.511984)
							(end 0.381 -0.3683)
						)
						(arc
							(start 0.381 0.3683)
							(mid 0.321484 0.511984)
							(end 0.1778 0.5715)
						)
					)
					(width 0)
					(fill yes)
				)
			)
		)
		(pad "G" smd custom
			(at -0.98425 0.9525 180)
			(size 0.1905 0.1905)
			(layers "F.Cu" "F.Mask" "F.Paste")
			(net "DRIVE_A_12_FLT_LED")
			(options
				(clearance outline)
				(anchor circle)
			)
			(primitives
				(gr_poly
					(pts
						(arc
							(start -0.1778 0.5715)
							(mid -0.321484 0.511984)
							(end -0.381 0.3683)
						)
						(arc
							(start -0.381 -0.3683)
							(mid -0.321484 -0.511984)
							(end -0.1778 -0.5715)
						)
						(arc
							(start 0.1778 -0.5715)
							(mid 0.321484 -0.511984)
							(end 0.381 -0.3683)
						)
						(arc
							(start 0.381 0.3683)
							(mid 0.321484 0.511984)
							(end 0.1778 0.5715)
						)
					)
					(width 0)
					(fill yes)
				)
			)
		)
		(pad "S" smd custom
			(at 0.98425 0.9525 180)
			(size 0.1905 0.1905)
			(layers "F.Cu" "F.Mask" "F.Paste")
			(net "GND")
			(options
				(clearance outline)
				(anchor circle)
			)
			(primitives
				(gr_poly
					(pts
						(arc
							(start -0.1778 0.5715)
							(mid -0.321484 0.511984)
							(end -0.381 0.3683)
						)
						(arc
							(start -0.381 -0.3683)
							(mid -0.321484 -0.511984)
							(end -0.1778 -0.5715)
						)
						(arc
							(start 0.1778 -0.5715)
							(mid 0.321484 -0.511984)
							(end 0.381 -0.3683)
						)
						(arc
							(start 0.381 0.3683)
							(mid 0.321484 0.511984)
							(end 0.1778 0.5715)
						)
					)
					(width 0)
					(fill yes)
				)
			)
		)
	)
)
